#ISCELL
  mstr_misc dns *
  *
#ISCELL
  mstr_symbols intel_corp_bpage *
  *
#ISCELL
  mstr_symbols pvddq_abc *
  page216_i1
#CELL
  mstr_discrete ir354xx *
  page216_i102
#CELL
  mstr_discrete ir354xx *
  page216_i103
#CELL
  mstr_discrete res *
  page216_i104
#ISCELL
  mstr_symbols gnd *
  page216_i105
#CELL
  mstr_discrete res *
  page216_i106
#ISCELL
  mstr_symbols gnd *
  page216_i107
#CELL
  dev_discrete cap_a *
  page216_i108
#ISCELL
  mstr_symbols gnd *
  page216_i109
#CELL
  dev_discrete cap_a *
  page216_i111
#ISCELL
  mstr_symbols gnd *
  page216_i112
#ISCELL
  mstr_symbols gnd *
  page216_i115
#ISCELL
  mstr_symbols gnd *
  page216_i117
#CELL
  mstr_discrete cap *
  page216_i118
#ISCELL
  mstr_symbols gnd *
  page216_i120
#CELL
  mstr_discrete cap *
  page216_i121
#ISCELL
  mstr_symbols gnd *
  page216_i122
#CELL
  mstr_discrete cap *
  page216_i128
#CELL
  mstr_discrete cap *
  page216_i135
#CELL
  mstr_discrete cap *
  page216_i136
#CELL
  mstr_discrete res *
  page216_i139
#CELL
  mstr_discrete res *
  page216_i140
#CELL
  mstr_discrete res *
  page216_i145
#CELL
  mstr_discrete res *
  page216_i146
#CELL
  w_hdl sc1u10v2kx-4-gp *
  page216_i149
#CELL
  w_hdl sc1u10v2kx-4-gp *
  page216_i150
#CELL
  w_hdl 1r3f-gp *
  page216_i151
#CELL
  w_hdl 1r3f-gp *
  page216_i152
#CELL
  w_hdl ind-120nh-30-gp *
  page216_i153
#CELL
  w_hdl ind-120nh-30-gp *
  page216_i155
#ISCELL
  mstr_symbols gnd *
  page216_i19
#ISCELL
  mstr_standard offpage *
  page216_i3
#ISCELL
  mstr_standard offpage *
  page216_i33
#ISCELL
  mstr_symbols gnd *
  page216_i35
#ISCELL
  mstr_standard offpage *
  page216_i4
#CELL
  mstr_discrete cap *
  page216_i44
#CELL
  mstr_discrete cap *
  page216_i45
#CELL
  mstr_discrete cap *
  page216_i46
#CELL
  mstr_discrete cap *
  page216_i47
#CELL
  mstr_discrete cap *
  page216_i48
#CELL
  mstr_discrete cap *
  page216_i50
#CELL
  dev_discrete cap_a *
  page216_i51
#CELL
  mstr_discrete cap *
  page216_i54
#ISCELL
  mstr_standard offpage *
  page216_i58
#CELL
  mstr_discrete cap *
  page216_i6
#ISCELL
  mstr_standard offpage *
  page216_i61
#ISCELL
  mstr_standard offpage *
  page216_i62
#ISCELL
  mstr_standard offpage *
  page216_i63
#ISCELL
  mstr_symbols pvddq_abc *
  page216_i64
#CELL
  mstr_discrete cap *
  page216_i68
#ISCELL
  mstr_symbols gnd *
  page216_i69
#ISCELL
  mstr_symbols gnd *
  page216_i7
#ISCELL
  mstr_symbols gnd *
  page216_i70
#CELL
  mstr_discrete cap *
  page216_i72
#CELL
  mstr_discrete cap *
  page216_i77
#CELL
  dev_discrete cap_a *
  page216_i78
#CELL
  mstr_discrete cap *
  page216_i79
#CELL
  mstr_discrete cap *
  page216_i80
#CELL
  mstr_discrete cap *
  page216_i81
#ISCELL
  mstr_standard offpage *
  page216_i82
#ISCELL
  mstr_symbols vcc_core *
  page216_i83
#CELL
  mstr_discrete cap *
  page216_i84
#ISCELL
  mstr_symbols gnd *
  page216_i85
#ISCELL
  mstr_symbols vcc_core *
  page216_i86
#ISCELL
  mstr_symbols p5v_stby *
  page216_i87
#ISCELL
  mstr_symbols p5v_stby *
  page216_i88
